# BASEBOARD_FAB2 (Tioga Pass) — schematic netlist excerpt (pin names and nets, part order shuffled) for the footprints in the layout excerpt that follows; sources: Cadence DE-HDL packaged netlist, KiCad conversion of Wiwynn_Tioga_Pass_MB.brd

J9U2  SCONN288_H44441003  SCONN  pkg PIP  page 82
  \12v\(1)  = P12V_NVDIMM_GHJ
  VSS(93)  = GND
  DQ(4)  = M_J_DQ<4>
  VSS(92)  = GND
  DQ(0)  = M_J_DQ<0>
  VSS(91)  = GND
  DQS9P  = M_J_DQS_DP<9>
  DQS9N  = M_J_DQS_DN<9>
  VSS(90)  = GND
  DQ(6)  = M_J_DQ<6>
  VSS(89)  = GND
  DQ(2)  = M_J_DQ<2>
  VSS(88)  = GND
  DQ(12)  = M_J_DQ<12>
  VSS(87)  = GND
  DQ(8)  = M_J_DQ<8>
  VSS(86)  = GND
  DQS10P  = M_J_DQS_DP<10>
  DQS10N  = M_J_DQS_DN<10>
  VSS(85)  = GND
  DQ(14)  = M_J_DQ<14>
  VSS(84)  = GND
  DQ(10)  = M_J_DQ<10>
  VSS(83)  = GND
  DQ(20)  = M_J_DQ<20>
  VSS(82)  = GND
  DQ(16)  = M_J_DQ<16>
  VSS(81)  = GND
  DQS11P  = M_J_DQS_DP<11>
  DQS11N  = M_J_DQS_DN<11>
  VSS(80)  = GND
  DQ(22)  = M_J_DQ<22>
  VSS(79)  = GND
  DQ(18)  = M_J_DQ<18>
  VSS(78)  = GND
  DQ(28)  = M_J_DQ<28>
  VSS(77)  = GND
  DQ(24)  = M_J_DQ<24>
  VSS(76)  = GND
  DQS12P  = M_J_DQS_DP<12>
  DQS12N  = M_J_DQS_DN<12>
  VSS(75)  = GND
  DQ(30)  = M_J_DQ<30>
  VSS(74)  = GND
  DQ(26)  = M_J_DQ<26>
  VSS(73)  = GND
  CB(4)  = M_J_ECC<4>
  VSS(72)  = GND
  CB(0)  = M_J_ECC<0>
  VSS(71)  = GND
  DQS17P  = M_J_DQS_DP<17>
  DQS17N  = M_J_DQS_DN<17>
  VSS(70)  = GND
  CB(6)  = M_J_ECC<6>
  VSS(69)  = GND
  CB(2)  = M_J_ECC<2>
  VSS(68)  = GND
  RESET_N  = M_GHJ_RST_N
  VDD(25)  = PVDDQ_GHJ
  CKE(0)  = M_J_CKE<2>
  VDD(24)  = PVDDQ_GHJ
  ACT_N  = M_J_ACT_N
  BG(0)  = M_J_BG<0>
  VDD(23)  = PVDDQ_GHJ
  A12  = M_J_MA<12>
  A9  = M_J_MA<9>
  VDD(22)  = PVDDQ_GHJ
  A8  = M_J_MA<8>
  A6  = M_J_MA<6>
  VDD(21)  = PVDDQ_GHJ
  A3  = M_J_MA<3>
  A1  = M_J_MA<1>
  VDD(20)  = PVDDQ_GHJ
  CK0P  = M_J_CLK_DP<2>
  CK0N  = M_J_CLK_DN<2>
  VDD(19)  = PVDDQ_GHJ
  VTT(1)  = PVTT_GHJ
  EVENT_N  = FM_DIMM_EVENT_COD_N
  A0  = M_J_MA<0>
  VDD(18)  = PVDDQ_GHJ
  BA(0)  = M_J_BA<0>
  A16_RAS_N  = M_J_MA<16>
  VDD(17)  = PVDDQ_GHJ
  S0_N  = M_J_CS_N<4>
  VDD(16)  = PVDDQ_GHJ
  A15_CAS_N  = M_J_MA<15>
  ODT(0)  = M_J_ODT<2>
  VDD(15)  = PVDDQ_GHJ
  S1_N  = M_J_CS_N<5>
  VDD(14)  = PVDDQ_GHJ
  ODT(1)  = M_J_ODT<3>
  VDD(13)  = PVDDQ_GHJ
  S2_N_C(0)  = M_J_CS_N<6>
  VSS(67)  = GND
  DQ(36)  = M_J_DQ<36>
  VSS(66)  = GND
  DQ(32)  = M_J_DQ<32>
  VSS(65)  = GND
  DQS13P  = M_J_DQS_DP<13>
  DQS13N  = M_J_DQS_DN<13>
  VSS(64)  = GND
  DQ(38)  = M_J_DQ<38>
  VSS(63)  = GND
  DQ(34)  = M_J_DQ<34>
  VSS(62)  = GND
  DQ(44)  = M_J_DQ<44>
  VSS(61)  = GND
  DQ(40)  = M_J_DQ<40>
  VSS(60)  = GND
  DQS14P  = M_J_DQS_DP<14>
  DQS14N  = M_J_DQS_DN<14>
  VSS(59)  = GND
  DQ(46)  = M_J_DQ<46>
  VSS(58)  = GND
  DQ(42)  = M_J_DQ<42>
  VSS(57)  = GND
  DQ(52)  = M_J_DQ<52>
  VSS(56)  = GND
  DQ(48)  = M_J_DQ<48>
  VSS(55)  = GND
  DQS15P  = M_J_DQS_DP<15>
  DQS15N  = M_J_DQS_DN<15>
  VSS(54)  = GND
  DQ(54)  = M_J_DQ<54>
  VSS(53)  = GND
  DQ(50)  = M_J_DQ<50>
  VSS(52)  = GND
  DQ(60)  = M_J_DQ<60>
  VSS(51)  = GND
  DQ(56)  = M_J_DQ<56>
  VSS(50)  = GND
  DQS16P  = M_J_DQS_DP<16>
  DQS16N  = M_J_DQS_DN<16>
  VSS(49)  = GND
  DQ(62)  = M_J_DQ<62>
  VSS(48)  = GND
  DQ(58)  = M_J_DQ<58>
  VSS(47)  = GND
  SA(0)  = PVPP_GHJ
  SA(1)  = GND
  SCL  = SMB_DDR_GHJ_VPP_SCL
  VPP(4)  = PVPP_GHJ
  VPP(3)  = PVPP_GHJ
  RFU(2)  = TP_CH_J_DIMM_J1_RFU_2
  \12v\(0)  = P12V_NVDIMM_GHJ
  VREFCA  = M_J_VREF
  VSS(46)  = GND
  DQ(5)  = M_J_DQ<5>
  VSS(45)  = GND
  DQ(1)  = M_J_DQ<1>
  VSS(44)  = GND
  DQS0N  = M_J_DQS_DN<0>
  DQS0P  = M_J_DQS_DP<0>
  VSS(43)  = GND
  DQ(7)  = M_J_DQ<7>
  VSS(42)  = GND
  DQ(3)  = M_J_DQ<3>
  VSS(41)  = GND
  DQ(13)  = M_J_DQ<13>
  VSS(40)  = GND
  DQ(9)  = M_J_DQ<9>
  VSS(39)  = GND
  DQS1N  = M_J_DQS_DN<1>
  DQS1P  = M_J_DQS_DP<1>
  VSS(38)  = GND
  DQ(15)  = M_J_DQ<15>
  VSS(37)  = GND
  DQ(11)  = M_J_DQ<11>
  VSS(36)  = GND
  DQ(21)  = M_J_DQ<21>
  VSS(35)  = GND
  DQ(17)  = M_J_DQ<17>
  VSS(34)  = GND
  DQS2N  = M_J_DQS_DN<2>
  DQS2P  = M_J_DQS_DP<2>
  VSS(33)  = GND
  DQ(23)  = M_J_DQ<23>
  VSS(32)  = GND
  DQ(19)  = M_J_DQ<19>
  VSS(31)  = GND
  DQ(29)  = M_J_DQ<29>
  VSS(30)  = GND
  DQ(25)  = M_J_DQ<25>
  VSS(29)  = GND
  DQS3N  = M_J_DQS_DN<3>
  DQS3P  = M_J_DQS_DP<3>
  VSS(28)  = GND
  DQ(31)  = M_J_DQ<31>
  VSS(27)  = GND
  DQ(27)  = M_J_DQ<27>
  VSS(26)  = GND
  CB(5)  = M_J_ECC<5>
  VSS(25)  = GND
  CB(1)  = M_J_ECC<1>
  VSS(24)  = GND
  DQS8N  = M_J_DQS_DN<8>
  DQS8P  = M_J_DQS_DP<8>
  VSS(23)  = GND
  CB(7)  = M_J_ECC<7>
  VSS(22)  = GND
  CB(3)  = M_J_ECC<3>
  VSS(21)  = GND
  CKE(1)  = M_J_CKE<3>
  VDD(12)  = PVDDQ_GHJ
  RFU(0)  = TP_CH_J_DIMM_J1_RFU_0
  VDD(11)  = PVDDQ_GHJ
  BG(1)  = M_J_BG<1>
  ALERT_N  = M_J_ALERT_N
  VDD(10)  = PVDDQ_GHJ
  A11  = M_J_MA<11>
  A7  = M_J_MA<7>
  VDD(9)  = PVDDQ_GHJ
  A5  = M_J_MA<5>
  A4  = M_J_MA<4>
  VDD(8)  = PVDDQ_GHJ
  A2  = M_J_MA<2>
  VDD(7)  = PVDDQ_GHJ
  CK1P  = M_J_CLK_DP<3>
  CK1N  = M_J_CLK_DN<3>
  VDD(6)  = PVDDQ_GHJ
  VTT(0)  = PVTT_GHJ
  PAR  = M_J_PAR
  VDD(5)  = PVDDQ_GHJ
  BA(1)  = M_J_BA<1>
  A10  = M_J_MA<10>
  VDD(4)  = PVDDQ_GHJ
  RFU(1)  = TP_CH_J_DIMM_J1_RFU_1
  A14_WE_N  = M_J_MA<14>
  VDD(3)  = PVDDQ_GHJ
  SAVE_N_NC  = FM_ADR_COMPLETE_GHJ_N
  VDD(2)  = PVDDQ_GHJ
  A13  = M_J_MA<13>
  VDD(1)  = PVDDQ_GHJ
  A17  = M_J_MA<17>
  C(2)  = M_J_C<2>
  VDD(0)  = PVDDQ_GHJ
  S3_N_C(1)  = M_J_CS_N<7>
  SA(2)  = PVPP_GHJ
  VSS(20)  = GND
  DQ(37)  = M_J_DQ<37>
  VSS(19)  = GND
  DQ(33)  = M_J_DQ<33>
  VSS(18)  = GND
  DQS4N  = M_J_DQS_DN<4>
  DQS4P  = M_J_DQS_DP<4>
  VSS(17)  = GND
  DQ(39)  = M_J_DQ<39>
  VSS(16)  = GND
  DQ(35)  = M_J_DQ<35>
  VSS(15)  = GND
  DQ(45)  = M_J_DQ<45>
  VSS(14)  = GND
  DQ(41)  = M_J_DQ<41>
  VSS(13)  = GND
  DQS5N  = M_J_DQS_DN<5>
  DQS5P  = M_J_DQS_DP<5>
  VSS(12)  = GND
  DQ(47)  = M_J_DQ<47>
  VSS(11)  = GND
  DQ(43)  = M_J_DQ<43>
  VSS(10)  = GND
  DQ(53)  = M_J_DQ<53>
  VSS(9)  = GND
  DQ(49)  = M_J_DQ<49>
  VSS(8)  = GND
  DQS6N  = M_J_DQS_DN<6>
  DQS6P  = M_J_DQS_DP<6>
  VSS(7)  = GND
  DQ(55)  = M_J_DQ<55>
  VSS(6)  = GND
  DQ(51)  = M_J_DQ<51>
  VSS(5)  = GND
  DQ(61)  = M_J_DQ<61>
  VSS(4)  = GND
  DQ(57)  = M_J_DQ<57>
  VSS(3)  = GND
  DQS7N  = M_J_DQS_DN<7>
  DQS7P  = M_J_DQS_DP<7>
  VSS(2)  = GND
  DQ(63)  = M_J_DQ<63>
  VSS(1)  = GND
  DQ(59)  = M_J_DQ<59>
  VSS(0)  = GND
  VDDSPD  = PVPP_GHJ
  SDA  = SMB_DDR_GHJ_VPP_SDA
  VPP(1)  = PVPP_GHJ
  VPP(0)  = PVPP_GHJ
  VPP(2)  = PVPP_GHJ

(kicad_pcb
	(version 20260206)
	(generator "pcbnew")
	(generator_version "10.0")
	(general
		(thickness 1.6)
		(legacy_teardrops no)
	)
	(paper "A4")
	(title_block
		(title "Wiwynn_Tioga_Pass_MB.brd")
		(comment 1 "Tioga Pass / footprint 4543 of 4770 (J9U2), pads 51-100 of 291")
	)
	(layers
		(0 "F.Cu" signal "TOP")
		(4 "In1.Cu" signal "L2GND")
		(6 "In2.Cu" signal "L3")
		(8 "In3.Cu" signal "L4GND")
		(10 "In4.Cu" signal "L5")
		(12 "In5.Cu" signal "L6GND")
		(14 "In6.Cu" signal "L7VCC")
		(16 "In7.Cu" signal "L8VCC")
		(18 "In8.Cu" signal "L9GND")
		(20 "In9.Cu" signal "L10")
		(22 "In10.Cu" signal "L11GND")
		(24 "In11.Cu" signal "L12")
		(26 "In12.Cu" signal "L13GND")
		(2 "B.Cu" signal "BOTTOM")
		(9 "F.Adhes" user "F.Adhesive")
		(11 "B.Adhes" user "B.Adhesive")
		(13 "F.Paste" user "Package Geometry/Pastemask Top")
		(15 "B.Paste" user "Package Geometry/Pastemask Bottom")
		(5 "F.SilkS" user "Ref Des/Silkscreen Top")
		(7 "B.SilkS" user "Ref Des/Silkscreen Bottom")
		(1 "F.Mask" user "Board Geometry/Soldermask Top")
		(3 "B.Mask" user "Board Geometry/Soldermask Bottom")
		(17 "Dwgs.User" user "User.Drawings")
		(19 "Cmts.User" user "User.Comments")
		(21 "Eco1.User" user "User.Eco1")
		(23 "Eco2.User" user "User.Eco2")
		(25 "Edge.Cuts" user "Board Geometry/Outline")
		(27 "Margin" user)
		(31 "F.CrtYd" user "Package Geometry/Place Bound Top")
		(29 "B.CrtYd" user "Package Geometry/Place Bound Bottom")
		(35 "F.Fab" user "Ref Des/Assembly Top")
		(33 "B.Fab" user "Ref Des/Assembly Bottom")
	)
	(footprint ""
		(layer "B.Cu")
		(at 29.699458 -5.621782 90)
		(property "Reference" "J9U2"
			(at 2.098548 38.118542 0)
			(unlocked yes)
			(layer "B.SilkS")
			(effects
				(font
					(size 0.7874 0.5842)
					(thickness 0.1524)
				)
				(justify left mirror)
			)
		)
		(property "Value" ""
			(at 0 0 90)
			(layer "B.Fab")
			(effects
				(font
					(size 1.27 1.27)
				)
				(justify mirror)
			)
		)
		(duplicate_pad_numbers_are_jumpers no)
		(pad "48" smd rect
			(at 0 39.949882 270)
			(size 1.8034 0.508)
			(layers "B.Cu" "B.Mask" "B.Paste")
			(net "GND")
		)
		(pad "49" smd rect
			(at 0 40.80002 270)
			(size 1.8034 0.508)
			(layers "B.Cu" "B.Mask" "B.Paste")
			(net "M_J_ECC<0>")
		)
		(pad "50" smd rect
			(at 0 41.649904 270)
			(size 1.8034 0.508)
			(layers "B.Cu" "B.Mask" "B.Paste")
			(net "GND")
		)
		(pad "51" smd rect
			(at 0 42.500042 270)
			(size 1.8034 0.508)
			(layers "B.Cu" "B.Mask" "B.Paste")
			(net "M_J_DQS_DP<17>")
		)
		(pad "52" smd rect
			(at 0 43.349926 270)
			(size 1.8034 0.508)
			(layers "B.Cu" "B.Mask" "B.Paste")
			(net "M_J_DQS_DN<17>")
		)
		(pad "53" smd rect
			(at 0 44.200064 270)
			(size 1.8034 0.508)
			(layers "B.Cu" "B.Mask" "B.Paste")
			(net "GND")
		)
		(pad "54" smd rect
			(at 0 45.049948 270)
			(size 1.8034 0.508)
			(layers "B.Cu" "B.Mask" "B.Paste")
			(net "M_J_ECC<6>")
		)
		(pad "55" smd rect
			(at 0 45.900086 270)
			(size 1.8034 0.508)
			(layers "B.Cu" "B.Mask" "B.Paste")
			(net "GND")
		)
		(pad "56" smd rect
			(at 0 46.74997 270)
			(size 1.8034 0.508)
			(layers "B.Cu" "B.Mask" "B.Paste")
			(net "M_J_ECC<2>")
		)
		(pad "57" smd rect
			(at 0 47.600108 270)
			(size 1.8034 0.508)
			(layers "B.Cu" "B.Mask" "B.Paste")
			(net "GND")
		)
		(pad "58" smd rect
			(at 0 48.449992 270)
			(size 1.8034 0.508)
			(layers "B.Cu" "B.Mask" "B.Paste")
			(net "M_GHJ_RST_N")
		)
		(pad "59" smd rect
			(at 0 49.299876 270)
			(size 1.8034 0.508)
			(layers "B.Cu" "B.Mask" "B.Paste")
			(net "PVDDQ_GHJ")
		)
		(pad "60" smd rect
			(at 0 50.150014 270)
			(size 1.8034 0.508)
			(layers "B.Cu" "B.Mask" "B.Paste")
			(net "M_J_CKE<2>")
		)
		(pad "61" smd rect
			(at 0 50.999898 270)
			(size 1.8034 0.508)
			(layers "B.Cu" "B.Mask" "B.Paste")
			(net "PVDDQ_GHJ")
		)
		(pad "62" smd rect
			(at 0 51.850036 270)
			(size 1.8034 0.508)
			(layers "B.Cu" "B.Mask" "B.Paste")
			(net "M_J_ACT_N")
		)
		(pad "63" smd rect
			(at 0 52.69992 270)
			(size 1.8034 0.508)
			(layers "B.Cu" "B.Mask" "B.Paste")
			(net "M_J_BG<0>")
		)
		(pad "64" smd rect
			(at 0 53.550058 270)
			(size 1.8034 0.508)
			(layers "B.Cu" "B.Mask" "B.Paste")
			(net "PVDDQ_GHJ")
		)
		(pad "65" smd rect
			(at 0 54.399942 270)
			(size 1.8034 0.508)
			(layers "B.Cu" "B.Mask" "B.Paste")
			(net "M_J_MA<12>")
		)
		(pad "66" smd rect
			(at 0 55.25008 270)
			(size 1.8034 0.508)
			(layers "B.Cu" "B.Mask" "B.Paste")
			(net "M_J_MA<9>")
		)
		(pad "67" smd rect
			(at 0 56.099964 270)
			(size 1.8034 0.508)
			(layers "B.Cu" "B.Mask" "B.Paste")
			(net "PVDDQ_GHJ")
		)
		(pad "68" smd rect
			(at 0 56.950102 270)
			(size 1.8034 0.508)
			(layers "B.Cu" "B.Mask" "B.Paste")
			(net "M_J_MA<8>")
		)
		(pad "69" smd rect
			(at 0 57.799986 270)
			(size 1.8034 0.508)
			(layers "B.Cu" "B.Mask" "B.Paste")
			(net "M_J_MA<6>")
		)
		(pad "70" smd rect
			(at 0 58.650124 270)
			(size 1.8034 0.508)
			(layers "B.Cu" "B.Mask" "B.Paste")
			(net "PVDDQ_GHJ")
		)
		(pad "71" smd rect
			(at 0 59.500008 270)
			(size 1.8034 0.508)
			(layers "B.Cu" "B.Mask" "B.Paste")
			(net "M_J_MA<3>")
		)
		(pad "72" smd rect
			(at 0 60.349892 270)
			(size 1.8034 0.508)
			(layers "B.Cu" "B.Mask" "B.Paste")
			(net "M_J_MA<1>")
		)
		(pad "73" smd rect
			(at 0 61.20003 270)
			(size 1.8034 0.508)
			(layers "B.Cu" "B.Mask" "B.Paste")
			(net "PVDDQ_GHJ")
		)
		(pad "74" smd rect
			(at 0 62.049914 270)
			(size 1.8034 0.508)
			(layers "B.Cu" "B.Mask" "B.Paste")
			(net "M_J_CLK_DP<2>")
		)
		(pad "75" smd rect
			(at 0 62.900052 270)
			(size 1.8034 0.508)
			(layers "B.Cu" "B.Mask" "B.Paste")
			(net "M_J_CLK_DN<2>")
		)
		(pad "76" smd rect
			(at 0 63.749936 270)
			(size 1.8034 0.508)
			(layers "B.Cu" "B.Mask" "B.Paste")
			(net "PVDDQ_GHJ")
		)
		(pad "77" smd rect
			(at 0 64.600074 270)
			(size 1.8034 0.508)
			(layers "B.Cu" "B.Mask" "B.Paste")
			(net "PVTT_GHJ")
		)
		(pad "78" smd rect
			(at 0 70.550024 270)
			(size 1.8034 0.508)
			(layers "B.Cu" "B.Mask" "B.Paste")
			(net "FM_DIMM_EVENT_COD_N")
		)
		(pad "79" smd rect
			(at 0 71.399908 270)
			(size 1.8034 0.508)
			(layers "B.Cu" "B.Mask" "B.Paste")
			(net "M_J_MA<0>")
		)
		(pad "80" smd rect
			(at 0 72.250046 270)
			(size 1.8034 0.508)
			(layers "B.Cu" "B.Mask" "B.Paste")
			(net "PVDDQ_GHJ")
		)
		(pad "81" smd rect
			(at 0 73.09993 270)
			(size 1.8034 0.508)
			(layers "B.Cu" "B.Mask" "B.Paste")
			(net "M_J_BA<0>")
		)
		(pad "82" smd rect
			(at 0 73.950068 270)
			(size 1.8034 0.508)
			(layers "B.Cu" "B.Mask" "B.Paste")
			(net "M_J_MA<16>")
		)
		(pad "83" smd rect
			(at 0 74.799952 270)
			(size 1.8034 0.508)
			(layers "B.Cu" "B.Mask" "B.Paste")
			(net "PVDDQ_GHJ")
		)
		(pad "84" smd rect
			(at 0 75.65009 270)
			(size 1.8034 0.508)
			(layers "B.Cu" "B.Mask" "B.Paste")
			(net "M_J_CS_N<4>")
		)
		(pad "85" smd rect
			(at 0 76.499974 270)
			(size 1.8034 0.508)
			(layers "B.Cu" "B.Mask" "B.Paste")
			(net "PVDDQ_GHJ")
		)
		(pad "86" smd rect
			(at 0 77.350112 270)
			(size 1.8034 0.508)
			(layers "B.Cu" "B.Mask" "B.Paste")
			(net "M_J_MA<15>")
		)
		(pad "87" smd rect
			(at 0 78.199996 270)
			(size 1.8034 0.508)
			(layers "B.Cu" "B.Mask" "B.Paste")
			(net "M_J_ODT<2>")
		)
		(pad "88" smd rect
			(at 0 79.04988 270)
			(size 1.8034 0.508)
			(layers "B.Cu" "B.Mask" "B.Paste")
			(net "PVDDQ_GHJ")
		)
		(pad "89" smd rect
			(at 0 79.900018 270)
			(size 1.8034 0.508)
			(layers "B.Cu" "B.Mask" "B.Paste")
			(net "M_J_CS_N<5>")
		)
		(pad "90" smd rect
			(at 0 80.749902 270)
			(size 1.8034 0.508)
			(layers "B.Cu" "B.Mask" "B.Paste")
			(net "PVDDQ_GHJ")
		)
		(pad "91" smd rect
			(at 0 81.60004 270)
			(size 1.8034 0.508)
			(layers "B.Cu" "B.Mask" "B.Paste")
			(net "M_J_ODT<3>")
		)
		(pad "92" smd rect
			(at 0 82.449924 270)
			(size 1.8034 0.508)
			(layers "B.Cu" "B.Mask" "B.Paste")
			(net "PVDDQ_GHJ")
		)
		(pad "93" smd rect
			(at 0 83.300062 270)
			(size 1.8034 0.508)
			(layers "B.Cu" "B.Mask" "B.Paste")
			(net "M_J_CS_N<6>")
		)
		(pad "94" smd rect
			(at 0 84.149946 270)
			(size 1.8034 0.508)
			(layers "B.Cu" "B.Mask" "B.Paste")
			(net "GND")
		)
		(pad "95" smd rect
			(at 0 85.000084 270)
			(size 1.8034 0.508)
			(layers "B.Cu" "B.Mask" "B.Paste")
			(net "M_J_DQ<36>")
		)
		(pad "96" smd rect
			(at 0 85.849968 270)
			(size 1.8034 0.508)
			(layers "B.Cu" "B.Mask" "B.Paste")
			(net "GND")
		)
		(pad "97" smd rect
			(at 0 86.700106 270)
			(size 1.8034 0.508)
			(layers "B.Cu" "B.Mask" "B.Paste")
			(net "M_J_DQ<32>")
		)
	)
)
